(kicad_pcb
	(version 20260206)
	(generator "pcbnew")
	(generator_version "10.0")
	(general
		(thickness 1.6)
		(legacy_teardrops no)
	)
	(paper "A4")
	(title_block
		(title "04192023_DAF0TMB3IC0_F0TG_MB_C_brd_V02_OCP.brd")
		(comment 1 "Grand Teton / footprints 1999-2005 of 8354")
	)
	(layers
		(0 "F.Cu" signal "TOP")
		(4 "In1.Cu" signal "GND")
		(6 "In2.Cu" signal "IN1")
		(8 "In3.Cu" signal "GND1")
		(10 "In4.Cu" signal "IN2")
		(12 "In5.Cu" signal "GND2")
		(14 "In6.Cu" signal "IN3")
		(16 "In7.Cu" signal "GND3")
		(18 "In8.Cu" signal "VCC")
		(20 "In9.Cu" signal "VCC1")
		(22 "In10.Cu" signal "GND4")
		(24 "In11.Cu" signal "IN4")
		(26 "In12.Cu" signal "GND5")
		(28 "In13.Cu" signal "IN5")
		(30 "In14.Cu" signal "GND6")
		(32 "In15.Cu" signal "IN6")
		(34 "In16.Cu" signal "GND7")
		(2 "B.Cu" signal "BOTTOM")
		(9 "F.Adhes" user "F.Adhesive")
		(11 "B.Adhes" user "B.Adhesive")
		(13 "F.Paste" user "Package Geometry/Pastemask Top")
		(15 "B.Paste" user "Package Geometry/Pastemask Bottom")
		(5 "F.SilkS" user "Ref Des/Silkscreen Top")
		(7 "B.SilkS" user "Ref Des/Silkscreen Bottom")
		(1 "F.Mask" user "Board Geometry/Soldermask Top")
		(3 "B.Mask" user "Board Geometry/Soldermask Bottom")
		(17 "Dwgs.User" user "User.Drawings")
		(19 "Cmts.User" user "User.Comments")
		(21 "Eco1.User" user "User.Eco1")
		(23 "Eco2.User" user "User.Eco2")
		(25 "Edge.Cuts" user "Board Geometry/Outline")
		(27 "Margin" user)
		(31 "F.CrtYd" user "Package Geometry/Place Bound Top")
		(29 "B.CrtYd" user "Package Geometry/Place Bound Bottom")
		(35 "F.Fab" user "Ref Des/Assembly Top")
		(33 "B.Fab" user "Ref Des/Assembly Bottom")
	)
	(footprint ""
		(layer "F.Cu")
		(at 24.765 -363.347 180)
		(property "Reference" "PC363"
			(at 0 0 180)
			(layer "F.SilkS")
			(hide yes)
			(effects
				(font
					(size 1.27 1.27)
				)
			)
		)
		(property "Value" ""
			(at 0 0 180)
			(layer "F.Fab")
			(effects
				(font
					(size 1.27 1.27)
				)
			)
		)
		(duplicate_pad_numbers_are_jumpers no)
		(fp_line
			(start 0.7874 0.4064)
			(end -0.7874 0.4064)
			(stroke
				(width 0.1524)
				(type default)
			)
			(layer "F.SilkS")
		)
		(fp_line
			(start 0.7874 -0.4064)
			(end 0.7874 0.4064)
			(stroke
				(width 0.1524)
				(type default)
			)
			(layer "F.SilkS")
		)
		(fp_line
			(start -0.7874 0.4064)
			(end -0.7874 -0.4064)
			(stroke
				(width 0.1524)
				(type default)
			)
			(layer "F.SilkS")
		)
		(fp_line
			(start -0.7874 -0.4064)
			(end 0.7874 -0.4064)
			(stroke
				(width 0.1524)
				(type default)
			)
			(layer "F.SilkS")
		)
		(fp_line
			(start 0.67945 0.3048)
			(end 0.120396 0.3048)
			(stroke
				(width 0.1)
				(type default)
			)
			(layer "F.Fab")
		)
		(fp_line
			(start 0.67945 -0.3048)
			(end 0.67945 0.3048)
			(stroke
				(width 0.1)
				(type default)
			)
			(layer "F.Fab")
		)
		(fp_line
			(start 0.12065 -0.2794)
			(end 0.12065 -0.3048)
			(stroke
				(width 0.1)
				(type default)
			)
			(layer "F.Fab")
		)
		(fp_line
			(start 0.12065 -0.3048)
			(end 0.67945 -0.3048)
			(stroke
				(width 0.1)
				(type default)
			)
			(layer "F.Fab")
		)
		(fp_line
			(start 0.120396 0.3048)
			(end 0.120396 0.2794)
			(stroke
				(width 0.1)
				(type default)
			)
			(layer "F.Fab")
		)
		(fp_line
			(start 0.120396 0.2794)
			(end -0.12065 0.2794)
			(stroke
				(width 0.1)
				(type default)
			)
			(layer "F.Fab")
		)
		(fp_line
			(start -0.12065 0.3048)
			(end -0.67945 0.3048)
			(stroke
				(width 0.1)
				(type default)
			)
			(layer "F.Fab")
		)
		(fp_line
			(start -0.12065 0.2794)
			(end -0.12065 0.3048)
			(stroke
				(width 0.1)
				(type default)
			)
			(layer "F.Fab")
		)
		(fp_line
			(start -0.12065 -0.2794)
			(end 0.12065 -0.2794)
			(stroke
				(width 0.1)
				(type default)
			)
			(layer "F.Fab")
		)
		(fp_line
			(start -0.12065 -0.305054)
			(end -0.12065 -0.2794)
			(stroke
				(width 0.1)
				(type default)
			)
			(layer "F.Fab")
		)
		(fp_line
			(start -0.67945 0.3048)
			(end -0.67945 -0.305054)
			(stroke
				(width 0.1)
				(type default)
			)
			(layer "F.Fab")
		)
		(fp_line
			(start -0.67945 -0.305054)
			(end -0.12065 -0.305054)
			(stroke
				(width 0.1)
				(type default)
			)
			(layer "F.Fab")
		)
		(pad "1" smd circle
			(at -0.40005 0 180)
			(size 0 0)
			(layers "F.Cu" "F.Mask" "F.Paste")
			(net "PVDD18_S5_P1")
		)
		(pad "2" smd circle
			(at 0.40005 0 180)
			(size 0 0)
			(layers "F.Cu" "F.Mask" "F.Paste")
			(net "GND")
		)
	)
	(footprint ""
		(layer "F.Cu")
		(at 49.276 -435.991 -90)
		(property "Reference" "C1770"
			(at 0 0 270)
			(layer "F.SilkS")
			(hide yes)
			(effects
				(font
					(size 1.27 1.27)
				)
			)
		)
		(property "Value" ""
			(at 0 0 270)
			(layer "F.Fab")
			(effects
				(font
					(size 1.27 1.27)
				)
			)
		)
		(duplicate_pad_numbers_are_jumpers no)
		(fp_line
			(start -0.7874 0.4064)
			(end -0.7874 -0.4064)
			(stroke
				(width 0.1524)
				(type default)
			)
			(layer "F.SilkS")
		)
		(fp_line
			(start 0.7874 0.4064)
			(end -0.7874 0.4064)
			(stroke
				(width 0.1524)
				(type default)
			)
			(layer "F.SilkS")
		)
		(fp_line
			(start -0.7874 -0.4064)
			(end 0.7874 -0.4064)
			(stroke
				(width 0.1524)
				(type default)
			)
			(layer "F.SilkS")
		)
		(fp_line
			(start 0.7874 -0.4064)
			(end 0.7874 0.4064)
			(stroke
				(width 0.1524)
				(type default)
			)
			(layer "F.SilkS")
		)
		(fp_line
			(start -0.67945 0.3048)
			(end -0.67945 -0.305054)
			(stroke
				(width 0.1)
				(type default)
			)
			(layer "F.Fab")
		)
		(fp_line
			(start -0.12065 0.3048)
			(end -0.67945 0.3048)
			(stroke
				(width 0.1)
				(type default)
			)
			(layer "F.Fab")
		)
		(fp_line
			(start 0.120396 0.3048)
			(end 0.120396 0.2794)
			(stroke
				(width 0.1)
				(type default)
			)
			(layer "F.Fab")
		)
		(fp_line
			(start 0.67945 0.3048)
			(end 0.120396 0.3048)
			(stroke
				(width 0.1)
				(type default)
			)
			(layer "F.Fab")
		)
		(fp_line
			(start -0.12065 0.2794)
			(end -0.12065 0.3048)
			(stroke
				(width 0.1)
				(type default)
			)
			(layer "F.Fab")
		)
		(fp_line
			(start 0.120396 0.2794)
			(end -0.12065 0.2794)
			(stroke
				(width 0.1)
				(type default)
			)
			(layer "F.Fab")
		)
		(fp_line
			(start -0.12065 -0.2794)
			(end 0.12065 -0.2794)
			(stroke
				(width 0.1)
				(type default)
			)
			(layer "F.Fab")
		)
		(fp_line
			(start 0.12065 -0.2794)
			(end 0.12065 -0.3048)
			(stroke
				(width 0.1)
				(type default)
			)
			(layer "F.Fab")
		)
		(fp_line
			(start 0.12065 -0.3048)
			(end 0.67945 -0.3048)
			(stroke
				(width 0.1)
				(type default)
			)
			(layer "F.Fab")
		)
		(fp_line
			(start 0.67945 -0.3048)
			(end 0.67945 0.3048)
			(stroke
				(width 0.1)
				(type default)
			)
			(layer "F.Fab")
		)
		(fp_line
			(start -0.67945 -0.305054)
			(end -0.12065 -0.305054)
			(stroke
				(width 0.1)
				(type default)
			)
			(layer "F.Fab")
		)
		(fp_line
			(start -0.12065 -0.305054)
			(end -0.12065 -0.2794)
			(stroke
				(width 0.1)
				(type default)
			)
			(layer "F.Fab")
		)
		(pad "1" smd circle
			(at -0.40005 0 270)
			(size 0 0)
			(layers "F.Cu" "F.Mask" "F.Paste")
			(net "P3V3_AUX")
		)
		(pad "2" smd circle
			(at 0.40005 0 270)
			(size 0 0)
			(layers "F.Cu" "F.Mask" "F.Paste")
			(net "GND")
		)
	)
	(footprint ""
		(layer "F.Cu")
		(at 111.251238 -39.40175 90)
		(property "Reference" "R6291"
			(at 0 0 90)
			(layer "F.SilkS")
			(hide yes)
			(effects
				(font
					(size 1.27 1.27)
				)
			)
		)
		(property "Value" ""
			(at 0 0 90)
			(layer "F.Fab")
			(effects
				(font
					(size 1.27 1.27)
				)
			)
		)
		(duplicate_pad_numbers_are_jumpers no)
		(fp_line
			(start 0.7874 -0.4064)
			(end 0.7874 0.4064)
			(stroke
				(width 0.1524)
				(type default)
			)
			(layer "F.SilkS")
		)
		(fp_line
			(start -0.7874 -0.4064)
			(end 0.7874 -0.4064)
			(stroke
				(width 0.1524)
				(type default)
			)
			(layer "F.SilkS")
		)
		(fp_line
			(start 0.7874 0.4064)
			(end -0.7874 0.4064)
			(stroke
				(width 0.1524)
				(type default)
			)
			(layer "F.SilkS")
		)
		(fp_line
			(start -0.7874 0.4064)
			(end -0.7874 -0.4064)
			(stroke
				(width 0.1524)
				(type default)
			)
			(layer "F.SilkS")
		)
		(fp_line
			(start -0.12065 -0.305054)
			(end -0.12065 -0.2794)
			(stroke
				(width 0.1)
				(type default)
			)
			(layer "F.Fab")
		)
		(fp_line
			(start -0.67945 -0.305054)
			(end -0.12065 -0.305054)
			(stroke
				(width 0.1)
				(type default)
			)
			(layer "F.Fab")
		)
		(fp_line
			(start 0.67945 -0.3048)
			(end 0.67945 0.3048)
			(stroke
				(width 0.1)
				(type default)
			)
			(layer "F.Fab")
		)
		(fp_line
			(start 0.12065 -0.3048)
			(end 0.67945 -0.3048)
			(stroke
				(width 0.1)
				(type default)
			)
			(layer "F.Fab")
		)
		(fp_line
			(start 0.12065 -0.2794)
			(end 0.12065 -0.3048)
			(stroke
				(width 0.1)
				(type default)
			)
			(layer "F.Fab")
		)
		(fp_line
			(start -0.12065 -0.2794)
			(end 0.12065 -0.2794)
			(stroke
				(width 0.1)
				(type default)
			)
			(layer "F.Fab")
		)
		(fp_line
			(start 0.120396 0.2794)
			(end -0.12065 0.2794)
			(stroke
				(width 0.1)
				(type default)
			)
			(layer "F.Fab")
		)
		(fp_line
			(start -0.12065 0.2794)
			(end -0.12065 0.3048)
			(stroke
				(width 0.1)
				(type default)
			)
			(layer "F.Fab")
		)
		(fp_line
			(start 0.67945 0.3048)
			(end 0.120396 0.3048)
			(stroke
				(width 0.1)
				(type default)
			)
			(layer "F.Fab")
		)
		(fp_line
			(start 0.120396 0.3048)
			(end 0.120396 0.2794)
			(stroke
				(width 0.1)
				(type default)
			)
			(layer "F.Fab")
		)
		(fp_line
			(start -0.12065 0.3048)
			(end -0.67945 0.3048)
			(stroke
				(width 0.1)
				(type default)
			)
			(layer "F.Fab")
		)
		(fp_line
			(start -0.67945 0.3048)
			(end -0.67945 -0.305054)
			(stroke
				(width 0.1)
				(type default)
			)
			(layer "F.Fab")
		)
		(pad "1" smd circle
			(at -0.40005 0 90)
			(size 0 0)
			(layers "F.Cu" "F.Mask" "F.Paste")
			(net "USB_HUB2_TI_GANGED_MRP_I2C_SLV_CFG0")
		)
		(pad "2" smd circle
			(at 0.40005 0 90)
			(size 0 0)
			(layers "F.Cu" "F.Mask" "F.Paste")
			(net "USB_HUB2_MRP_I2C_SLV_CFG0")
		)
	)
	(footprint ""
		(layer "F.Cu")
		(at 105.515156 -344.591132 -90)
		(property "Reference" "PC146"
			(at 0 0 270)
			(layer "F.SilkS")
			(hide yes)
			(effects
				(font
					(size 1.27 1.27)
				)
			)
		)
		(property "Value" ""
			(at 0 0 270)
			(layer "F.Fab")
			(effects
				(font
					(size 1.27 1.27)
				)
			)
		)
		(duplicate_pad_numbers_are_jumpers no)
		(fp_line
			(start -0.7874 0.4064)
			(end -0.7874 -0.4064)
			(stroke
				(width 0.1524)
				(type default)
			)
			(layer "F.SilkS")
		)
		(fp_line
			(start 0.7874 0.4064)
			(end -0.7874 0.4064)
			(stroke
				(width 0.1524)
				(type default)
			)
			(layer "F.SilkS")
		)
		(fp_line
			(start -0.7874 -0.4064)
			(end 0.7874 -0.4064)
			(stroke
				(width 0.1524)
				(type default)
			)
			(layer "F.SilkS")
		)
		(fp_line
			(start 0.7874 -0.4064)
			(end 0.7874 0.4064)
			(stroke
				(width 0.1524)
				(type default)
			)
			(layer "F.SilkS")
		)
		(fp_line
			(start -0.67945 0.3048)
			(end -0.67945 -0.305054)
			(stroke
				(width 0.1)
				(type default)
			)
			(layer "F.Fab")
		)
		(fp_line
			(start -0.12065 0.3048)
			(end -0.67945 0.3048)
			(stroke
				(width 0.1)
				(type default)
			)
			(layer "F.Fab")
		)
		(fp_line
			(start 0.120396 0.3048)
			(end 0.120396 0.2794)
			(stroke
				(width 0.1)
				(type default)
			)
			(layer "F.Fab")
		)
		(fp_line
			(start 0.67945 0.3048)
			(end 0.120396 0.3048)
			(stroke
				(width 0.1)
				(type default)
			)
			(layer "F.Fab")
		)
		(fp_line
			(start -0.12065 0.2794)
			(end -0.12065 0.3048)
			(stroke
				(width 0.1)
				(type default)
			)
			(layer "F.Fab")
		)
		(fp_line
			(start 0.120396 0.2794)
			(end -0.12065 0.2794)
			(stroke
				(width 0.1)
				(type default)
			)
			(layer "F.Fab")
		)
		(fp_line
			(start -0.12065 -0.2794)
			(end 0.12065 -0.2794)
			(stroke
				(width 0.1)
				(type default)
			)
			(layer "F.Fab")
		)
		(fp_line
			(start 0.12065 -0.2794)
			(end 0.12065 -0.3048)
			(stroke
				(width 0.1)
				(type default)
			)
			(layer "F.Fab")
		)
		(fp_line
			(start 0.12065 -0.3048)
			(end 0.67945 -0.3048)
			(stroke
				(width 0.1)
				(type default)
			)
			(layer "F.Fab")
		)
		(fp_line
			(start 0.67945 -0.3048)
			(end 0.67945 0.3048)
			(stroke
				(width 0.1)
				(type default)
			)
			(layer "F.Fab")
		)
		(fp_line
			(start -0.67945 -0.305054)
			(end -0.12065 -0.305054)
			(stroke
				(width 0.1)
				(type default)
			)
			(layer "F.Fab")
		)
		(fp_line
			(start -0.12065 -0.305054)
			(end -0.12065 -0.2794)
			(stroke
				(width 0.1)
				(type default)
			)
			(layer "F.Fab")
		)
		(pad "1" smd circle
			(at -0.40005 0 270)
			(size 0 0)
			(layers "F.Cu" "F.Mask" "F.Paste")
			(net "SW_PVDDCR_CPU1_P1_BOOT6_R")
		)
		(pad "2" smd circle
			(at 0.40005 0 270)
			(size 0 0)
			(layers "F.Cu" "F.Mask" "F.Paste")
			(net "SW_PVDDCR_CPU1_P1_BOOTR6")
		)
	)
	(footprint ""
		(layer "F.Cu")
		(at 75.7936 -384.66268)
		(property "Reference" "R783"
			(at 0 0 0)
			(layer "F.SilkS")
			(hide yes)
			(effects
				(font
					(size 1.27 1.27)
				)
			)
		)
		(property "Value" ""
			(at 0 0 0)
			(layer "F.Fab")
			(effects
				(font
					(size 1.27 1.27)
				)
			)
		)
		(duplicate_pad_numbers_are_jumpers no)
		(fp_line
			(start -0.32512 -0.175006)
			(end 0.32512 -0.175006)
			(stroke
				(width 0.1)
				(type default)
			)
			(layer "F.Fab")
		)
		(fp_line
			(start -0.32512 0.175006)
			(end -0.32512 -0.175006)
			(stroke
				(width 0.1)
				(type default)
			)
			(layer "F.Fab")
		)
		(fp_line
			(start 0.32512 -0.175006)
			(end 0.32512 0.175006)
			(stroke
				(width 0.1)
				(type default)
			)
			(layer "F.Fab")
		)
		(fp_line
			(start 0.32512 0.175006)
			(end -0.32512 0.175006)
			(stroke
				(width 0.1)
				(type default)
			)
			(layer "F.Fab")
		)
		(pad "1" smd rect
			(at -0.2667 0)
			(size 0.3048 0.381)
			(layers "F.Cu" "F.Mask" "F.Paste")
			(net "GPIO3_RT_CPU1_P1")
		)
		(pad "2" smd rect
			(at 0.2667 0 180)
			(size 0.3048 0.381)
			(layers "F.Cu" "F.Mask" "F.Paste")
			(net "GND")
		)
	)
	(footprint ""
		(layer "F.Cu")
		(at 100.046282 -339.937598 -90)
		(property "Reference" "PC139_C1P1_6"
			(at 0 0 270)
			(layer "F.SilkS")
			(hide yes)
			(effects
				(font
					(size 1.27 1.27)
				)
			)
		)
		(property "Value" ""
			(at 0 0 270)
			(layer "F.Fab")
			(effects
				(font
					(size 1.27 1.27)
				)
			)
		)
		(duplicate_pad_numbers_are_jumpers no)
		(fp_line
			(start -0.7874 0.4064)
			(end -0.7874 -0.4064)
			(stroke
				(width 0.1524)
				(type default)
			)
			(layer "F.SilkS")
		)
		(fp_line
			(start 0.7874 0.4064)
			(end -0.7874 0.4064)
			(stroke
				(width 0.1524)
				(type default)
			)
			(layer "F.SilkS")
		)
		(fp_line
			(start -0.7874 -0.4064)
			(end 0.7874 -0.4064)
			(stroke
				(width 0.1524)
				(type default)
			)
			(layer "F.SilkS")
		)
		(fp_line
			(start 0.7874 -0.4064)
			(end 0.7874 0.4064)
			(stroke
				(width 0.1524)
				(type default)
			)
			(layer "F.SilkS")
		)
		(fp_line
			(start -0.67945 0.3048)
			(end -0.67945 -0.305054)
			(stroke
				(width 0.1)
				(type default)
			)
			(layer "F.Fab")
		)
		(fp_line
			(start -0.12065 0.3048)
			(end -0.67945 0.3048)
			(stroke
				(width 0.1)
				(type default)
			)
			(layer "F.Fab")
		)
		(fp_line
			(start 0.120396 0.3048)
			(end 0.120396 0.2794)
			(stroke
				(width 0.1)
				(type default)
			)
			(layer "F.Fab")
		)
		(fp_line
			(start 0.67945 0.3048)
			(end 0.120396 0.3048)
			(stroke
				(width 0.1)
				(type default)
			)
			(layer "F.Fab")
		)
		(fp_line
			(start -0.12065 0.2794)
			(end -0.12065 0.3048)
			(stroke
				(width 0.1)
				(type default)
			)
			(layer "F.Fab")
		)
		(fp_line
			(start 0.120396 0.2794)
			(end -0.12065 0.2794)
			(stroke
				(width 0.1)
				(type default)
			)
			(layer "F.Fab")
		)
		(fp_line
			(start -0.12065 -0.2794)
			(end 0.12065 -0.2794)
			(stroke
				(width 0.1)
				(type default)
			)
			(layer "F.Fab")
		)
		(fp_line
			(start 0.12065 -0.2794)
			(end 0.12065 -0.3048)
			(stroke
				(width 0.1)
				(type default)
			)
			(layer "F.Fab")
		)
		(fp_line
			(start 0.12065 -0.3048)
			(end 0.67945 -0.3048)
			(stroke
				(width 0.1)
				(type default)
			)
			(layer "F.Fab")
		)
		(fp_line
			(start 0.67945 -0.3048)
			(end 0.67945 0.3048)
			(stroke
				(width 0.1)
				(type default)
			)
			(layer "F.Fab")
		)
		(fp_line
			(start -0.67945 -0.305054)
			(end -0.12065 -0.305054)
			(stroke
				(width 0.1)
				(type default)
			)
			(layer "F.Fab")
		)
		(fp_line
			(start -0.12065 -0.305054)
			(end -0.12065 -0.2794)
			(stroke
				(width 0.1)
				(type default)
			)
			(layer "F.Fab")
		)
		(pad "1" smd circle
			(at -0.40005 0 270)
			(size 0 0)
			(layers "F.Cu" "F.Mask" "F.Paste")
			(net "PVDDCR_CPU1_P1_PVCC")
		)
		(pad "2" smd circle
			(at 0.40005 0 270)
			(size 0 0)
			(layers "F.Cu" "F.Mask" "F.Paste")
			(net "GND")
		)
	)
	(footprint ""
		(layer "F.Cu")
		(at 376.33402 -423.904918 180)
		(property "Reference" "R1127"
			(at 0 0 180)
			(layer "F.SilkS")
			(hide yes)
			(effects
				(font
					(size 1.27 1.27)
				)
			)
		)
		(property "Value" ""
			(at 0 0 180)
			(layer "F.Fab")
			(effects
				(font
					(size 1.27 1.27)
				)
			)
		)
		(duplicate_pad_numbers_are_jumpers no)
		(fp_line
			(start 0.32512 0.175006)
			(end -0.32512 0.175006)
			(stroke
				(width 0.1)
				(type default)
			)
			(layer "F.Fab")
		)
		(fp_line
			(start 0.32512 -0.175006)
			(end 0.32512 0.175006)
			(stroke
				(width 0.1)
				(type default)
			)
			(layer "F.Fab")
		)
		(fp_line
			(start -0.32512 0.175006)
			(end -0.32512 -0.175006)
			(stroke
				(width 0.1)
				(type default)
			)
			(layer "F.Fab")
		)
		(fp_line
			(start -0.32512 -0.175006)
			(end 0.32512 -0.175006)
			(stroke
				(width 0.1)
				(type default)
			)
			(layer "F.Fab")
		)
		(pad "1" smd rect
			(at -0.2667 0 180)
			(size 0.3048 0.381)
			(layers "F.Cu" "F.Mask" "F.Paste")
			(net "U17_E2")
		)
		(pad "2" smd rect
			(at 0.2667 0)
			(size 0.3048 0.381)
			(layers "F.Cu" "F.Mask" "F.Paste")
			(net "GND")
		)
	)
)
